FILE_TYPE = MACRO_DRAWING;
SET COLOR_WIRE YELLOW;
SET COLOR_PROP ORANGE;
SET COLOR_DOT WHITE;
SET COLOR_ARC YELLOW;
SET COLOR_BODY GREEN;
SET COLOR_NOTE PURPLE;
SET PROP_DISPLAY VALUE;
SET PAGE_NUMBER P38;
SET PATH_NUMBER P3;
FORCEADD LCMXO3LF2100C5BG256C..5
(-4775 4475);
FORCEPROP 1 LAST PART_NUMBER AJ021000T03
J 0
(-5264 5223);
DISPLAY 0.723404 (-5264 5223);
PAINT GREEN (-5264 5223);
FORCEPROP 1 LAST MATERIAL IC
J 0
(-5264 5132);
DISPLAY 0.723404 (-5264 5132);
PAINT GREEN (-5264 5132);
FORCEPROP 2 LAST PART_TYPE SMLF
J 0
(-5250 5425);
DISPLAY 0.680851 (-5250 5425);
FORCEPROP 2 LAST VALUE LCMXO3LF-2100C-5BG256C
J 0
(-5250 5375);
DISPLAY 0.680851 (-5250 5375);
FORCEPROP 1 LAST CDS_LMAN_SYM_OUTLINE -500,650,500,-650
J 0
(-4775 4475);
DISPLAY 0.468085 (-4775 4475);
PAINT GREEN (-4775 4475);
DISPLAY INVISIBLE (-4775 4475);
FORCEPROP 1 LAST NEEDS_NO_SIZE TRUE
J 0
(-4775 4475);
DISPLAY 0.723404 (-4775 4475);
PAINT GREEN (-4775 4475);
DISPLAY INVISIBLE (-4775 4475);
FORCEPROP 1 LAST PATH I1
J 0
(-4775 4475);
DISPLAY 0.723404 (-4775 4475);
PAINT GREEN (-4775 4475);
DISPLAY INVISIBLE (-4775 4475);
FORCEPROP 2 LAST CDS_LIB pure_quanta
J 0
(-4775 4475);
DISPLAY INVISIBLE (-4775 4475);
FORCEPROP 1 LAST LOCATION U25
J 0
(-5264 5322);
DISPLAY 0.723404 (-5264 5322);
PAINT GREEN (-5264 5322);
FORCEPROP 0 LASTPIN (-5425 4975) $PN G1
J 2
(-5435 4985);
DISPLAY 0.680851 (-5435 4985);
PAINT MONO (-5435 4985);
FORCEPROP 0 LASTPIN (-5425 4925) $PN H2
J 2
(-5435 4935);
DISPLAY 0.680851 (-5435 4935);
PAINT MONO (-5435 4935);
FORCEPROP 0 LASTPIN (-5425 4825) $PN H4
J 2
(-5435 4835);
DISPLAY 0.680851 (-5435 4835);
PAINT MONO (-5435 4835);
FORCEPROP 0 LASTPIN (-5425 4775) $PN J6
J 2
(-5435 4785);
DISPLAY 0.680851 (-5435 4785);
PAINT MONO (-5435 4785);
FORCEPROP 0 LASTPIN (-5425 4675) $PN H3
J 2
(-5435 4685);
DISPLAY 0.680851 (-5435 4685);
PAINT MONO (-5435 4685);
FORCEPROP 0 LASTPIN (-5425 4625) $PN H1
J 2
(-5435 4635);
DISPLAY 0.680851 (-5435 4635);
PAINT MONO (-5435 4635);
FORCEPROP 0 LASTPIN (-5425 4375) $PN J1
J 2
(-5435 4385);
DISPLAY 0.680851 (-5435 4385);
PAINT MONO (-5435 4385);
FORCEPROP 0 LASTPIN (-5425 4325) $PN J3
J 2
(-5435 4335);
DISPLAY 0.680851 (-5435 4335);
PAINT MONO (-5435 4335);
FORCEPROP 0 LASTPIN (-4125 4975) $PN J2
J 0
(-4115 4985);
DISPLAY 0.680851 (-4115 4985);
PAINT MONO (-4115 4985);
FORCEPROP 0 LASTPIN (-4125 4925) $PN K1
J 0
(-4115 4935);
DISPLAY 0.680851 (-4115 4935);
PAINT MONO (-4115 4935);
FORCEPROP 0 LASTPIN (-4125 4825) $PN H5
J 0
(-4115 4835);
DISPLAY 0.680851 (-4115 4835);
PAINT MONO (-4115 4835);
FORCEPROP 0 LASTPIN (-4125 4775) $PN J4
J 0
(-4115 4785);
DISPLAY 0.680851 (-4115 4785);
PAINT MONO (-4115 4785);
FORCEPROP 0 LASTPIN (-4125 4525) $PN K3
J 0
(-4115 4535);
DISPLAY 0.680851 (-4115 4535);
PAINT MONO (-4115 4535);
FORCEPROP 0 LASTPIN (-4125 4475) $PN K2
J 0
(-4115 4485);
DISPLAY 0.680851 (-4115 4485);
PAINT MONO (-4115 4485);
FORCEPROP 0 LASTPIN (-4125 4675) $PN J5
J 0
(-4115 4685);
DISPLAY 0.680851 (-4115 4685);
PAINT MONO (-4115 4685);
FORCEPROP 0 LASTPIN (-4125 4625) $PN K6
J 0
(-4115 4635);
DISPLAY 0.680851 (-4115 4635);
PAINT MONO (-4115 4635);
FORCEPROP 0 LASTPIN (-4125 4075) $PN H7
J 0
(-4115 4085);
DISPLAY 0.680851 (-4115 4085);
PAINT MONO (-4115 4085);
FORCEPROP 0 LASTPIN (-4125 4025) $PN J7
J 0
(-4115 4035);
DISPLAY 0.680851 (-4115 4035);
PAINT MONO (-4115 4035);
FORCEPROP 0 LAST $SEC 5
J 0
(-5250 5475);
DISPLAY 0.680851 (-5250 5475);
PAINT MONO (-5250 5475);
DISPLAY INVISIBLE (-5250 5475);
FORCEPROP 0 LAST CDS_SEC 5
J 0
(-5250 5475);
DISPLAY 0.680851 (-5250 5475);
DISPLAY INVISIBLE (-5250 5475);
FORCEADD UNIVERSAL_POWER..1
(-3750 4175);
FORCEPROP 3 LASTPIN (-3750 4125) SIG_NAME VCCIO4\g
J 0
(-3740 4135);
DISPLAY 0.659574 (-3740 4135);
PAINT MONO (-3740 4135);
DISPLAY INVISIBLE (-3740 4135);
FORCEPROP 1 LAST HDL_POWER VCCIO4
J 1
(-3750 4225);
DISPLAY 0.702128 (-3750 4225);
PAINT GREEN (-3750 4225);
FORCEPROP 2 LAST CDS_LIB logical_power
J 0
(-3750 4175);
DISPLAY INVISIBLE (-3750 4175);
FORCEPROP 1 LAST PATH I3
J 0
(-3700 4200);
DISPLAY 0.872340 (-3700 4200);
PAINT AQUA (-3700 4200);
DISPLAY INVISIBLE (-3700 4200);
FORCEADD QUANTA_TITLE_BLOCK_C..1
(0 0);
FORCEPROP 0 LAST CDS_CON_LAST_MODIFIED Fri Aug 25 17:25:44 2023
J 0
(-1885 15);
DISPLAY INVISIBLE (-1885 15);
FORCEPROP 2 LAST Q_DEPT 
J 1
(-3763 49);
DISPLAY 1.957447 (-3763 49);
PAINT GREEN (-3763 49);
FORCEPROP 1 LAST CUSTOM_TXT_CDS <CON_LAST_MODIFIED>
J 0
(-1885 15);
DISPLAY 0.978723 (-1885 15);
FORCEPROP 2 LAST CUSTOM_TXT_CDS <XR_PAGE_TITLE>
J 0
(-7890 5250);
DISPLAY 0.638298 (-7890 5250);
PAINT PINK (-7890 5250);
DISPLAY INVISIBLE (-7890 5250);
FORCEPROP 1 LAST CUSTOM_TXT_CDS <NAME_2>
J 0
(-3175 50);
FORCEPROP 1 LAST CUSTOM_TXT_CDS <NAME_1>
J 0
(-3175 175);
FORCEPROP 1 LAST CUSTOM_TXT_CDS <Q_NUMBER>
J 0
(-1403 103);
DISPLAY 1.212766 (-1403 103);
FORCEPROP 1 LAST CUSTOM_TXT_CDS <Q_PROJ>
J 0
(-2382 102);
DISPLAY 1.212766 (-2382 102);
FORCEPROP 1 LAST CUSTOM_TXT_CDS <Q_REV>
J 0
(-184 103);
DISPLAY 1.212766 (-184 103);
FORCEPROP 1 LAST CUSTOM_TXT_CDS <CON_PAGE_NUM> OF <CON_TOTAL_PAGES>
J 0
(-446 18);
DISPLAY 0.978723 (-446 18);
FORCEPROP 1 LAST Q_TITLE FPGA 5/8
J 0
(-9366 26);
DISPLAY 2.446809 (-9366 26);
PAINT GREEN (-9366 26);
FORCEPROP 2 LAST CDS_LIB pure_quanta
J 0
(0 0);
DISPLAY INVISIBLE (0 0);
FORCEPROP 1 LAST COMMENT_BODY TRUE
J 0
(12 -13);
DISPLAY 0.978723 (12 -13);
PAINT GREEN (12 -13);
DISPLAY INVISIBLE (12 -13);
FORCEPROP 1 LAST CDS_LMAN_SYM_OUTLINE -9475,6775,100,-125
J 0
(0 0);
DISPLAY 0.468085 (0 0);
PAINT GREEN (0 0);
DISPLAY INVISIBLE (0 0);
FORCEPROP 2 LAST PAGE_BORDER TRUE
J 0
(-7890 5250);
DISPLAY 0.638298 (-7890 5250);
PAINT PINK (-7890 5250);
DISPLAY INVISIBLE (-7890 5250);
FORCEPROP 2 LAST CDS_XR_PAGE_TITLE CR-38 : @SCM_LIB.SCM(SCH_1):PAGE38
J 0
(-7890 5250);
DISPLAY 0.638298 (-7890 5250);
PAINT PINK (-7890 5250);
DISPLAY INVISIBLE (-7890 5250);
WIRE 16 -1 (-3750 4125)(-3750 4075);
WIRE 16 -1 (-3925 4075)(-4125 4075);
WIRE 16 -1 (-3750 4075)(-3925 4075);
WIRE 16 -1 (-3925 4025)(-3925 4075);
WIRE 16 -1 (-4125 4025)(-3925 4025);
DOT 1 (-3925 4075);
QUIT
